# T6G (Grand Teton) — schematic netlist excerpt (pin names and nets, part order shuffled) for the footprints in the layout excerpt that follows; sources: Cadence DE-HDL packaged netlist, KiCad conversion of 04192023_DAF0TMB3IC0_F0TG_MB_C_brd_V02_OCP.brd

R4197  Q_RES  1K 1% CHIP  pkg 0402LF  page 235 : A = U271_1_ADD1 ; B = GND
R1458  Q_RES  33 5% CHIP  pkg 0402LF  page 259 : A = PWRGD_P12V_MEM_CPU0 ; B = PWRGD_P12V_MEM_CPU0_R

(kicad_pcb
	(version 20260206)
	(generator "pcbnew")
	(generator_version "10.0")
	(general
		(thickness 1.6)
		(legacy_teardrops no)
	)
	(paper "A4")
	(title_block
		(title "04192023_DAF0TMB3IC0_F0TG_MB_C_brd_V02_OCP.brd")
		(comment 1 "Grand Teton / footprints 4893-4894 of 8354")
	)
	(layers
		(0 "F.Cu" signal "TOP")
		(4 "In1.Cu" signal "GND")
		(6 "In2.Cu" signal "IN1")
		(8 "In3.Cu" signal "GND1")
		(10 "In4.Cu" signal "IN2")
		(12 "In5.Cu" signal "GND2")
		(14 "In6.Cu" signal "IN3")
		(16 "In7.Cu" signal "GND3")
		(18 "In8.Cu" signal "VCC")
		(20 "In9.Cu" signal "VCC1")
		(22 "In10.Cu" signal "GND4")
		(24 "In11.Cu" signal "IN4")
		(26 "In12.Cu" signal "GND5")
		(28 "In13.Cu" signal "IN5")
		(30 "In14.Cu" signal "GND6")
		(32 "In15.Cu" signal "IN6")
		(34 "In16.Cu" signal "GND7")
		(2 "B.Cu" signal "BOTTOM")
		(9 "F.Adhes" user "F.Adhesive")
		(11 "B.Adhes" user "B.Adhesive")
		(13 "F.Paste" user "Package Geometry/Pastemask Top")
		(15 "B.Paste" user "Package Geometry/Pastemask Bottom")
		(5 "F.SilkS" user "Ref Des/Silkscreen Top")
		(7 "B.SilkS" user "Ref Des/Silkscreen Bottom")
		(1 "F.Mask" user "Board Geometry/Soldermask Top")
		(3 "B.Mask" user "Board Geometry/Soldermask Bottom")
		(17 "Dwgs.User" user "User.Drawings")
		(19 "Cmts.User" user "User.Comments")
		(21 "Eco1.User" user "User.Eco1")
		(23 "Eco2.User" user "User.Eco2")
		(25 "Edge.Cuts" user "Board Geometry/Outline")
		(27 "Margin" user)
		(31 "F.CrtYd" user "Package Geometry/Place Bound Top")
		(29 "B.CrtYd" user "Package Geometry/Place Bound Bottom")
		(35 "F.Fab" user "Ref Des/Assembly Top")
		(33 "B.Fab" user "Ref Des/Assembly Bottom")
	)
	(footprint ""
		(layer "F.Cu")
		(at 303.374298 -14.48181)
		(property "Reference" "R4197"
			(at 0 0 0)
			(layer "F.SilkS")
			(hide yes)
			(effects
				(font
					(size 1.27 1.27)
				)
			)
		)
		(property "Value" ""
			(at 0 0 0)
			(layer "F.Fab")
			(effects
				(font
					(size 1.27 1.27)
				)
			)
		)
		(duplicate_pad_numbers_are_jumpers no)
		(fp_line
			(start -0.7874 -0.4064)
			(end 0.7874 -0.4064)
			(stroke
				(width 0.1524)
				(type default)
			)
			(layer "F.SilkS")
		)
		(fp_line
			(start -0.7874 0.4064)
			(end -0.7874 -0.4064)
			(stroke
				(width 0.1524)
				(type default)
			)
			(layer "F.SilkS")
		)
		(fp_line
			(start 0.7874 -0.4064)
			(end 0.7874 0.4064)
			(stroke
				(width 0.1524)
				(type default)
			)
			(layer "F.SilkS")
		)
		(fp_line
			(start 0.7874 0.4064)
			(end -0.7874 0.4064)
			(stroke
				(width 0.1524)
				(type default)
			)
			(layer "F.SilkS")
		)
		(fp_line
			(start -0.67945 -0.305054)
			(end -0.12065 -0.305054)
			(stroke
				(width 0.1)
				(type default)
			)
			(layer "F.Fab")
		)
		(fp_line
			(start -0.67945 0.3048)
			(end -0.67945 -0.305054)
			(stroke
				(width 0.1)
				(type default)
			)
			(layer "F.Fab")
		)
		(fp_line
			(start -0.12065 -0.305054)
			(end -0.12065 -0.2794)
			(stroke
				(width 0.1)
				(type default)
			)
			(layer "F.Fab")
		)
		(fp_line
			(start -0.12065 -0.2794)
			(end 0.12065 -0.2794)
			(stroke
				(width 0.1)
				(type default)
			)
			(layer "F.Fab")
		)
		(fp_line
			(start -0.12065 0.2794)
			(end -0.12065 0.3048)
			(stroke
				(width 0.1)
				(type default)
			)
			(layer "F.Fab")
		)
		(fp_line
			(start -0.12065 0.3048)
			(end -0.67945 0.3048)
			(stroke
				(width 0.1)
				(type default)
			)
			(layer "F.Fab")
		)
		(fp_line
			(start 0.120396 0.2794)
			(end -0.12065 0.2794)
			(stroke
				(width 0.1)
				(type default)
			)
			(layer "F.Fab")
		)
		(fp_line
			(start 0.120396 0.3048)
			(end 0.120396 0.2794)
			(stroke
				(width 0.1)
				(type default)
			)
			(layer "F.Fab")
		)
		(fp_line
			(start 0.12065 -0.3048)
			(end 0.67945 -0.3048)
			(stroke
				(width 0.1)
				(type default)
			)
			(layer "F.Fab")
		)
		(fp_line
			(start 0.12065 -0.2794)
			(end 0.12065 -0.3048)
			(stroke
				(width 0.1)
				(type default)
			)
			(layer "F.Fab")
		)
		(fp_line
			(start 0.67945 -0.3048)
			(end 0.67945 0.3048)
			(stroke
				(width 0.1)
				(type default)
			)
			(layer "F.Fab")
		)
		(fp_line
			(start 0.67945 0.3048)
			(end 0.120396 0.3048)
			(stroke
				(width 0.1)
				(type default)
			)
			(layer "F.Fab")
		)
		(pad "1" smd circle
			(at -0.40005 0)
			(size 0 0)
			(layers "F.Cu" "F.Mask" "F.Paste")
			(net "U271_1_ADD1")
		)
		(pad "2" smd circle
			(at 0.40005 0)
			(size 0 0)
			(layers "F.Cu" "F.Mask" "F.Paste")
			(net "GND")
		)
	)
	(footprint ""
		(layer "F.Cu")
		(at 99.614736 -127.787654 -90)
		(property "Reference" "R1458"
			(at 0 0 270)
			(layer "F.SilkS")
			(hide yes)
			(effects
				(font
					(size 1.27 1.27)
				)
			)
		)
		(property "Value" ""
			(at 0 0 270)
			(layer "F.Fab")
			(effects
				(font
					(size 1.27 1.27)
				)
			)
		)
		(duplicate_pad_numbers_are_jumpers no)
		(fp_line
			(start -0.7874 0.4064)
			(end -0.7874 -0.4064)
			(stroke
				(width 0.1524)
				(type default)
			)
			(layer "F.SilkS")
		)
		(fp_line
			(start 0.7874 0.4064)
			(end -0.7874 0.4064)
			(stroke
				(width 0.1524)
				(type default)
			)
			(layer "F.SilkS")
		)
		(fp_line
			(start -0.7874 -0.4064)
			(end 0.7874 -0.4064)
			(stroke
				(width 0.1524)
				(type default)
			)
			(layer "F.SilkS")
		)
		(fp_line
			(start 0.7874 -0.4064)
			(end 0.7874 0.4064)
			(stroke
				(width 0.1524)
				(type default)
			)
			(layer "F.SilkS")
		)
		(fp_line
			(start -0.67945 0.3048)
			(end -0.67945 -0.305054)
			(stroke
				(width 0.1)
				(type default)
			)
			(layer "F.Fab")
		)
		(fp_line
			(start -0.12065 0.3048)
			(end -0.67945 0.3048)
			(stroke
				(width 0.1)
				(type default)
			)
			(layer "F.Fab")
		)
		(fp_line
			(start 0.120396 0.3048)
			(end 0.120396 0.2794)
			(stroke
				(width 0.1)
				(type default)
			)
			(layer "F.Fab")
		)
		(fp_line
			(start 0.67945 0.3048)
			(end 0.120396 0.3048)
			(stroke
				(width 0.1)
				(type default)
			)
			(layer "F.Fab")
		)
		(fp_line
			(start -0.12065 0.2794)
			(end -0.12065 0.3048)
			(stroke
				(width 0.1)
				(type default)
			)
			(layer "F.Fab")
		)
		(fp_line
			(start 0.120396 0.2794)
			(end -0.12065 0.2794)
			(stroke
				(width 0.1)
				(type default)
			)
			(layer "F.Fab")
		)
		(fp_line
			(start -0.12065 -0.2794)
			(end 0.12065 -0.2794)
			(stroke
				(width 0.1)
				(type default)
			)
			(layer "F.Fab")
		)
		(fp_line
			(start 0.12065 -0.2794)
			(end 0.12065 -0.3048)
			(stroke
				(width 0.1)
				(type default)
			)
			(layer "F.Fab")
		)
		(fp_line
			(start 0.12065 -0.3048)
			(end 0.67945 -0.3048)
			(stroke
				(width 0.1)
				(type default)
			)
			(layer "F.Fab")
		)
		(fp_line
			(start 0.67945 -0.3048)
			(end 0.67945 0.3048)
			(stroke
				(width 0.1)
				(type default)
			)
			(layer "F.Fab")
		)
		(fp_line
			(start -0.67945 -0.305054)
			(end -0.12065 -0.305054)
			(stroke
				(width 0.1)
				(type default)
			)
			(layer "F.Fab")
		)
		(fp_line
			(start -0.12065 -0.305054)
			(end -0.12065 -0.2794)
			(stroke
				(width 0.1)
				(type default)
			)
			(layer "F.Fab")
		)
		(pad "1" smd circle
			(at -0.40005 0 270)
			(size 0 0)
			(layers "F.Cu" "F.Mask" "F.Paste")
			(net "PWRGD_P12V_MEM_CPU0")
		)
		(pad "2" smd circle
			(at 0.40005 0 270)
			(size 0 0)
			(layers "F.Cu" "F.Mask" "F.Paste")
			(net "PWRGD_P12V_MEM_CPU0_R")
		)
	)
)
